(kicad_pcb
	(version 20260206)
	(generator "pcbnew")
	(generator_version "10.0")
	(general
		(thickness 1.6)
		(legacy_teardrops no)
	)
	(paper "A4")
	(title_block
		(title "03242023_DA0F0TMBIJ0_F0T_Motherboard_J_brd_V01_OCP.brd")
		(comment 1 "Grand Teton / footprints 287-292 of 6105")
	)
	(layers
		(0 "F.Cu" signal "TOP")
		(4 "In1.Cu" signal "GND")
		(6 "In2.Cu" signal "IN1")
		(8 "In3.Cu" signal "GND1")
		(10 "In4.Cu" signal "IN2")
		(12 "In5.Cu" signal "GND2")
		(14 "In6.Cu" signal "IN3")
		(16 "In7.Cu" signal "GND3")
		(18 "In8.Cu" signal "VCC")
		(20 "In9.Cu" signal "VCC1")
		(22 "In10.Cu" signal "GND4")
		(24 "In11.Cu" signal "IN4")
		(26 "In12.Cu" signal "GND5")
		(28 "In13.Cu" signal "IN5")
		(30 "In14.Cu" signal "GND6")
		(32 "In15.Cu" signal "IN6")
		(34 "In16.Cu" signal "GND7")
		(2 "B.Cu" signal "BOTTOM")
		(9 "F.Adhes" user "F.Adhesive")
		(11 "B.Adhes" user "B.Adhesive")
		(13 "F.Paste" user "Package Geometry/Pastemask Top")
		(15 "B.Paste" user "Package Geometry/Pastemask Bottom")
		(5 "F.SilkS" user "Ref Des/Silkscreen Top")
		(7 "B.SilkS" user "Ref Des/Silkscreen Bottom")
		(1 "F.Mask" user "Board Geometry/Soldermask Top")
		(3 "B.Mask" user "Board Geometry/Soldermask Bottom")
		(17 "Dwgs.User" user "User.Drawings")
		(19 "Cmts.User" user "User.Comments")
		(21 "Eco1.User" user "User.Eco1")
		(23 "Eco2.User" user "User.Eco2")
		(25 "Edge.Cuts" user "Board Geometry/Outline")
		(27 "Margin" user)
		(31 "F.CrtYd" user "Package Geometry/Place Bound Top")
		(29 "B.CrtYd" user "Package Geometry/Place Bound Bottom")
		(35 "F.Fab" user "Ref Des/Assembly Top")
		(33 "B.Fab" user "Ref Des/Assembly Bottom")
	)
	(footprint ""
		(layer "F.Cu")
		(at 342.803734 -27.488388 -90)
		(property "Reference" "R635"
			(at 0 0 270)
			(layer "F.SilkS")
			(hide yes)
			(effects
				(font
					(size 1.27 1.27)
				)
			)
		)
		(property "Value" ""
			(at 0 0 270)
			(layer "F.Fab")
			(effects
				(font
					(size 1.27 1.27)
				)
			)
		)
		(duplicate_pad_numbers_are_jumpers no)
		(fp_line
			(start -0.7874 0.4064)
			(end -0.7874 -0.4064)
			(stroke
				(width 0.1524)
				(type default)
			)
			(layer "F.SilkS")
		)
		(fp_line
			(start 0.7874 0.4064)
			(end -0.7874 0.4064)
			(stroke
				(width 0.1524)
				(type default)
			)
			(layer "F.SilkS")
		)
		(fp_line
			(start -0.7874 -0.4064)
			(end 0.7874 -0.4064)
			(stroke
				(width 0.1524)
				(type default)
			)
			(layer "F.SilkS")
		)
		(fp_line
			(start 0.7874 -0.4064)
			(end 0.7874 0.4064)
			(stroke
				(width 0.1524)
				(type default)
			)
			(layer "F.SilkS")
		)
		(fp_line
			(start -0.67945 0.3048)
			(end -0.67945 -0.305054)
			(stroke
				(width 0.1)
				(type default)
			)
			(layer "F.Fab")
		)
		(fp_line
			(start -0.12065 0.3048)
			(end -0.67945 0.3048)
			(stroke
				(width 0.1)
				(type default)
			)
			(layer "F.Fab")
		)
		(fp_line
			(start 0.120396 0.3048)
			(end 0.120396 0.2794)
			(stroke
				(width 0.1)
				(type default)
			)
			(layer "F.Fab")
		)
		(fp_line
			(start 0.67945 0.3048)
			(end 0.120396 0.3048)
			(stroke
				(width 0.1)
				(type default)
			)
			(layer "F.Fab")
		)
		(fp_line
			(start -0.12065 0.2794)
			(end -0.12065 0.3048)
			(stroke
				(width 0.1)
				(type default)
			)
			(layer "F.Fab")
		)
		(fp_line
			(start 0.120396 0.2794)
			(end -0.12065 0.2794)
			(stroke
				(width 0.1)
				(type default)
			)
			(layer "F.Fab")
		)
		(fp_line
			(start -0.12065 -0.2794)
			(end 0.12065 -0.2794)
			(stroke
				(width 0.1)
				(type default)
			)
			(layer "F.Fab")
		)
		(fp_line
			(start 0.12065 -0.2794)
			(end 0.12065 -0.3048)
			(stroke
				(width 0.1)
				(type default)
			)
			(layer "F.Fab")
		)
		(fp_line
			(start 0.12065 -0.3048)
			(end 0.67945 -0.3048)
			(stroke
				(width 0.1)
				(type default)
			)
			(layer "F.Fab")
		)
		(fp_line
			(start 0.67945 -0.3048)
			(end 0.67945 0.3048)
			(stroke
				(width 0.1)
				(type default)
			)
			(layer "F.Fab")
		)
		(fp_line
			(start -0.67945 -0.305054)
			(end -0.12065 -0.305054)
			(stroke
				(width 0.1)
				(type default)
			)
			(layer "F.Fab")
		)
		(fp_line
			(start -0.12065 -0.305054)
			(end -0.12065 -0.2794)
			(stroke
				(width 0.1)
				(type default)
			)
			(layer "F.Fab")
		)
		(pad "1" smd circle
			(at -0.40005 0 270)
			(size 0 0)
			(layers "F.Cu" "F.Mask" "F.Paste")
			(net "PU_OC3_USB_N")
		)
		(pad "2" smd circle
			(at 0.40005 0 270)
			(size 0 0)
			(layers "F.Cu" "F.Mask" "F.Paste")
			(net "P3V3_AUX")
		)
	)
	(footprint ""
		(layer "F.Cu")
		(at 98.045016 -338.180172 90)
		(property "Reference" "PR1767"
			(at 0 0 90)
			(layer "F.SilkS")
			(hide yes)
			(effects
				(font
					(size 1.27 1.27)
				)
			)
		)
		(property "Value" ""
			(at 0 0 90)
			(layer "F.Fab")
			(effects
				(font
					(size 1.27 1.27)
				)
			)
		)
		(duplicate_pad_numbers_are_jumpers no)
		(fp_line
			(start 0.7874 -0.4064)
			(end 0.7874 0.4064)
			(stroke
				(width 0.1524)
				(type default)
			)
			(layer "F.SilkS")
		)
		(fp_line
			(start -0.7874 -0.4064)
			(end 0.7874 -0.4064)
			(stroke
				(width 0.1524)
				(type default)
			)
			(layer "F.SilkS")
		)
		(fp_line
			(start 0.7874 0.4064)
			(end -0.7874 0.4064)
			(stroke
				(width 0.1524)
				(type default)
			)
			(layer "F.SilkS")
		)
		(fp_line
			(start -0.7874 0.4064)
			(end -0.7874 -0.4064)
			(stroke
				(width 0.1524)
				(type default)
			)
			(layer "F.SilkS")
		)
		(fp_line
			(start -0.12065 -0.305054)
			(end -0.12065 -0.2794)
			(stroke
				(width 0.1)
				(type default)
			)
			(layer "F.Fab")
		)
		(fp_line
			(start -0.67945 -0.305054)
			(end -0.12065 -0.305054)
			(stroke
				(width 0.1)
				(type default)
			)
			(layer "F.Fab")
		)
		(fp_line
			(start 0.67945 -0.3048)
			(end 0.67945 0.3048)
			(stroke
				(width 0.1)
				(type default)
			)
			(layer "F.Fab")
		)
		(fp_line
			(start 0.12065 -0.3048)
			(end 0.67945 -0.3048)
			(stroke
				(width 0.1)
				(type default)
			)
			(layer "F.Fab")
		)
		(fp_line
			(start 0.12065 -0.2794)
			(end 0.12065 -0.3048)
			(stroke
				(width 0.1)
				(type default)
			)
			(layer "F.Fab")
		)
		(fp_line
			(start -0.12065 -0.2794)
			(end 0.12065 -0.2794)
			(stroke
				(width 0.1)
				(type default)
			)
			(layer "F.Fab")
		)
		(fp_line
			(start 0.120396 0.2794)
			(end -0.12065 0.2794)
			(stroke
				(width 0.1)
				(type default)
			)
			(layer "F.Fab")
		)
		(fp_line
			(start -0.12065 0.2794)
			(end -0.12065 0.3048)
			(stroke
				(width 0.1)
				(type default)
			)
			(layer "F.Fab")
		)
		(fp_line
			(start 0.67945 0.3048)
			(end 0.120396 0.3048)
			(stroke
				(width 0.1)
				(type default)
			)
			(layer "F.Fab")
		)
		(fp_line
			(start 0.120396 0.3048)
			(end 0.120396 0.2794)
			(stroke
				(width 0.1)
				(type default)
			)
			(layer "F.Fab")
		)
		(fp_line
			(start -0.12065 0.3048)
			(end -0.67945 0.3048)
			(stroke
				(width 0.1)
				(type default)
			)
			(layer "F.Fab")
		)
		(fp_line
			(start -0.67945 0.3048)
			(end -0.67945 -0.305054)
			(stroke
				(width 0.1)
				(type default)
			)
			(layer "F.Fab")
		)
		(pad "1" smd circle
			(at -0.40005 0 90)
			(size 0 0)
			(layers "F.Cu" "F.Mask" "F.Paste")
			(net "SW_PVCCIN_CPU1_BOOT1")
		)
		(pad "2" smd circle
			(at 0.40005 0 90)
			(size 0 0)
			(layers "F.Cu" "F.Mask" "F.Paste")
			(net "SW_PVCCIN_CPU1_BOOT1_R")
		)
	)
	(footprint ""
		(layer "F.Cu")
		(at 27.628596 -393.342876)
		(property "Reference" "R3270"
			(at 0 0 0)
			(layer "F.SilkS")
			(hide yes)
			(effects
				(font
					(size 1.27 1.27)
				)
			)
		)
		(property "Value" ""
			(at 0 0 0)
			(layer "F.Fab")
			(effects
				(font
					(size 1.27 1.27)
				)
			)
		)
		(duplicate_pad_numbers_are_jumpers no)
		(fp_line
			(start -0.7874 -0.4064)
			(end 0.7874 -0.4064)
			(stroke
				(width 0.1524)
				(type default)
			)
			(layer "F.SilkS")
		)
		(fp_line
			(start -0.7874 0.4064)
			(end -0.7874 -0.4064)
			(stroke
				(width 0.1524)
				(type default)
			)
			(layer "F.SilkS")
		)
		(fp_line
			(start 0.7874 -0.4064)
			(end 0.7874 0.4064)
			(stroke
				(width 0.1524)
				(type default)
			)
			(layer "F.SilkS")
		)
		(fp_line
			(start 0.7874 0.4064)
			(end -0.7874 0.4064)
			(stroke
				(width 0.1524)
				(type default)
			)
			(layer "F.SilkS")
		)
		(fp_line
			(start -0.67945 -0.305054)
			(end -0.12065 -0.305054)
			(stroke
				(width 0.1)
				(type default)
			)
			(layer "F.Fab")
		)
		(fp_line
			(start -0.67945 0.3048)
			(end -0.67945 -0.305054)
			(stroke
				(width 0.1)
				(type default)
			)
			(layer "F.Fab")
		)
		(fp_line
			(start -0.12065 -0.305054)
			(end -0.12065 -0.2794)
			(stroke
				(width 0.1)
				(type default)
			)
			(layer "F.Fab")
		)
		(fp_line
			(start -0.12065 -0.2794)
			(end 0.12065 -0.2794)
			(stroke
				(width 0.1)
				(type default)
			)
			(layer "F.Fab")
		)
		(fp_line
			(start -0.12065 0.2794)
			(end -0.12065 0.3048)
			(stroke
				(width 0.1)
				(type default)
			)
			(layer "F.Fab")
		)
		(fp_line
			(start -0.12065 0.3048)
			(end -0.67945 0.3048)
			(stroke
				(width 0.1)
				(type default)
			)
			(layer "F.Fab")
		)
		(fp_line
			(start 0.120396 0.2794)
			(end -0.12065 0.2794)
			(stroke
				(width 0.1)
				(type default)
			)
			(layer "F.Fab")
		)
		(fp_line
			(start 0.120396 0.3048)
			(end 0.120396 0.2794)
			(stroke
				(width 0.1)
				(type default)
			)
			(layer "F.Fab")
		)
		(fp_line
			(start 0.12065 -0.3048)
			(end 0.67945 -0.3048)
			(stroke
				(width 0.1)
				(type default)
			)
			(layer "F.Fab")
		)
		(fp_line
			(start 0.12065 -0.2794)
			(end 0.12065 -0.3048)
			(stroke
				(width 0.1)
				(type default)
			)
			(layer "F.Fab")
		)
		(fp_line
			(start 0.67945 -0.3048)
			(end 0.67945 0.3048)
			(stroke
				(width 0.1)
				(type default)
			)
			(layer "F.Fab")
		)
		(fp_line
			(start 0.67945 0.3048)
			(end 0.120396 0.3048)
			(stroke
				(width 0.1)
				(type default)
			)
			(layer "F.Fab")
		)
		(pad "1" smd circle
			(at -0.40005 0)
			(size 0 0)
			(layers "F.Cu" "F.Mask" "F.Paste")
			(net "FM_P2E_FGB")
		)
		(pad "2" smd circle
			(at 0.40005 0)
			(size 0 0)
			(layers "F.Cu" "F.Mask" "F.Paste")
			(net "GND")
		)
	)
	(footprint ""
		(layer "F.Cu")
		(at 75.424538 -19.220942)
		(property "Reference" "PC2146"
			(at 0 0 0)
			(layer "F.SilkS")
			(hide yes)
			(effects
				(font
					(size 1.27 1.27)
				)
			)
		)
		(property "Value" ""
			(at 0 0 0)
			(layer "F.Fab")
			(effects
				(font
					(size 1.27 1.27)
				)
			)
		)
		(duplicate_pad_numbers_are_jumpers no)
		(fp_line
			(start -0.7874 -0.4064)
			(end 0.7874 -0.4064)
			(stroke
				(width 0.1524)
				(type default)
			)
			(layer "F.SilkS")
		)
		(fp_line
			(start -0.7874 0.4064)
			(end -0.7874 -0.4064)
			(stroke
				(width 0.1524)
				(type default)
			)
			(layer "F.SilkS")
		)
		(fp_line
			(start 0.7874 -0.4064)
			(end 0.7874 0.4064)
			(stroke
				(width 0.1524)
				(type default)
			)
			(layer "F.SilkS")
		)
		(fp_line
			(start 0.7874 0.4064)
			(end -0.7874 0.4064)
			(stroke
				(width 0.1524)
				(type default)
			)
			(layer "F.SilkS")
		)
		(fp_line
			(start -0.67945 -0.305054)
			(end -0.12065 -0.305054)
			(stroke
				(width 0.1)
				(type default)
			)
			(layer "F.Fab")
		)
		(fp_line
			(start -0.67945 0.3048)
			(end -0.67945 -0.305054)
			(stroke
				(width 0.1)
				(type default)
			)
			(layer "F.Fab")
		)
		(fp_line
			(start -0.12065 -0.305054)
			(end -0.12065 -0.2794)
			(stroke
				(width 0.1)
				(type default)
			)
			(layer "F.Fab")
		)
		(fp_line
			(start -0.12065 -0.2794)
			(end 0.12065 -0.2794)
			(stroke
				(width 0.1)
				(type default)
			)
			(layer "F.Fab")
		)
		(fp_line
			(start -0.12065 0.2794)
			(end -0.12065 0.3048)
			(stroke
				(width 0.1)
				(type default)
			)
			(layer "F.Fab")
		)
		(fp_line
			(start -0.12065 0.3048)
			(end -0.67945 0.3048)
			(stroke
				(width 0.1)
				(type default)
			)
			(layer "F.Fab")
		)
		(fp_line
			(start 0.120396 0.2794)
			(end -0.12065 0.2794)
			(stroke
				(width 0.1)
				(type default)
			)
			(layer "F.Fab")
		)
		(fp_line
			(start 0.120396 0.3048)
			(end 0.120396 0.2794)
			(stroke
				(width 0.1)
				(type default)
			)
			(layer "F.Fab")
		)
		(fp_line
			(start 0.12065 -0.3048)
			(end 0.67945 -0.3048)
			(stroke
				(width 0.1)
				(type default)
			)
			(layer "F.Fab")
		)
		(fp_line
			(start 0.12065 -0.2794)
			(end 0.12065 -0.3048)
			(stroke
				(width 0.1)
				(type default)
			)
			(layer "F.Fab")
		)
		(fp_line
			(start 0.67945 -0.3048)
			(end 0.67945 0.3048)
			(stroke
				(width 0.1)
				(type default)
			)
			(layer "F.Fab")
		)
		(fp_line
			(start 0.67945 0.3048)
			(end 0.120396 0.3048)
			(stroke
				(width 0.1)
				(type default)
			)
			(layer "F.Fab")
		)
		(pad "1" smd circle
			(at -0.40005 0)
			(size 0 0)
			(layers "F.Cu" "F.Mask" "F.Paste")
			(net "GND")
		)
		(pad "2" smd circle
			(at 0.40005 0)
			(size 0 0)
			(layers "F.Cu" "F.Mask" "F.Paste")
			(net "P12V_OCP_REG_2")
		)
	)
	(footprint ""
		(layer "F.Cu")
		(at 24.580596 -388.008876 -90)
		(property "Reference" "C1863"
			(at 0 0 270)
			(layer "F.SilkS")
			(hide yes)
			(effects
				(font
					(size 1.27 1.27)
				)
			)
		)
		(property "Value" ""
			(at 0 0 270)
			(layer "F.Fab")
			(effects
				(font
					(size 1.27 1.27)
				)
			)
		)
		(duplicate_pad_numbers_are_jumpers no)
		(fp_line
			(start -0.7874 0.4064)
			(end -0.7874 -0.4064)
			(stroke
				(width 0.1524)
				(type default)
			)
			(layer "F.SilkS")
		)
		(fp_line
			(start 0.7874 0.4064)
			(end -0.7874 0.4064)
			(stroke
				(width 0.1524)
				(type default)
			)
			(layer "F.SilkS")
		)
		(fp_line
			(start -0.7874 -0.4064)
			(end 0.7874 -0.4064)
			(stroke
				(width 0.1524)
				(type default)
			)
			(layer "F.SilkS")
		)
		(fp_line
			(start 0.7874 -0.4064)
			(end 0.7874 0.4064)
			(stroke
				(width 0.1524)
				(type default)
			)
			(layer "F.SilkS")
		)
		(fp_line
			(start -0.67945 0.3048)
			(end -0.67945 -0.305054)
			(stroke
				(width 0.1)
				(type default)
			)
			(layer "F.Fab")
		)
		(fp_line
			(start -0.12065 0.3048)
			(end -0.67945 0.3048)
			(stroke
				(width 0.1)
				(type default)
			)
			(layer "F.Fab")
		)
		(fp_line
			(start 0.120396 0.3048)
			(end 0.120396 0.2794)
			(stroke
				(width 0.1)
				(type default)
			)
			(layer "F.Fab")
		)
		(fp_line
			(start 0.67945 0.3048)
			(end 0.120396 0.3048)
			(stroke
				(width 0.1)
				(type default)
			)
			(layer "F.Fab")
		)
		(fp_line
			(start -0.12065 0.2794)
			(end -0.12065 0.3048)
			(stroke
				(width 0.1)
				(type default)
			)
			(layer "F.Fab")
		)
		(fp_line
			(start 0.120396 0.2794)
			(end -0.12065 0.2794)
			(stroke
				(width 0.1)
				(type default)
			)
			(layer "F.Fab")
		)
		(fp_line
			(start -0.12065 -0.2794)
			(end 0.12065 -0.2794)
			(stroke
				(width 0.1)
				(type default)
			)
			(layer "F.Fab")
		)
		(fp_line
			(start 0.12065 -0.2794)
			(end 0.12065 -0.3048)
			(stroke
				(width 0.1)
				(type default)
			)
			(layer "F.Fab")
		)
		(fp_line
			(start 0.12065 -0.3048)
			(end 0.67945 -0.3048)
			(stroke
				(width 0.1)
				(type default)
			)
			(layer "F.Fab")
		)
		(fp_line
			(start 0.67945 -0.3048)
			(end 0.67945 0.3048)
			(stroke
				(width 0.1)
				(type default)
			)
			(layer "F.Fab")
		)
		(fp_line
			(start -0.67945 -0.305054)
			(end -0.12065 -0.305054)
			(stroke
				(width 0.1)
				(type default)
			)
			(layer "F.Fab")
		)
		(fp_line
			(start -0.12065 -0.305054)
			(end -0.12065 -0.2794)
			(stroke
				(width 0.1)
				(type default)
			)
			(layer "F.Fab")
		)
		(pad "1" smd circle
			(at -0.40005 0 270)
			(size 0 0)
			(layers "F.Cu" "F.Mask" "F.Paste")
			(net "P3V3_AUX")
		)
		(pad "2" smd circle
			(at 0.40005 0 270)
			(size 0 0)
			(layers "F.Cu" "F.Mask" "F.Paste")
			(net "GND")
		)
	)
	(footprint ""
		(layer "F.Cu")
		(at 85.260942 -339.738462 90)
		(property "Reference" "PC501"
			(at 0 0 90)
			(layer "F.SilkS")
			(hide yes)
			(effects
				(font
					(size 1.27 1.27)
				)
			)
		)
		(property "Value" ""
			(at 0 0 90)
			(layer "F.Fab")
			(effects
				(font
					(size 1.27 1.27)
				)
			)
		)
		(duplicate_pad_numbers_are_jumpers no)
		(fp_line
			(start 0.7874 -0.4064)
			(end 0.7874 0.4064)
			(stroke
				(width 0.1524)
				(type default)
			)
			(layer "F.SilkS")
		)
		(fp_line
			(start -0.7874 -0.4064)
			(end 0.7874 -0.4064)
			(stroke
				(width 0.1524)
				(type default)
			)
			(layer "F.SilkS")
		)
		(fp_line
			(start 0.7874 0.4064)
			(end -0.7874 0.4064)
			(stroke
				(width 0.1524)
				(type default)
			)
			(layer "F.SilkS")
		)
		(fp_line
			(start -0.7874 0.4064)
			(end -0.7874 -0.4064)
			(stroke
				(width 0.1524)
				(type default)
			)
			(layer "F.SilkS")
		)
		(fp_line
			(start -0.12065 -0.305054)
			(end -0.12065 -0.2794)
			(stroke
				(width 0.1)
				(type default)
			)
			(layer "F.Fab")
		)
		(fp_line
			(start -0.67945 -0.305054)
			(end -0.12065 -0.305054)
			(stroke
				(width 0.1)
				(type default)
			)
			(layer "F.Fab")
		)
		(fp_line
			(start 0.67945 -0.3048)
			(end 0.67945 0.3048)
			(stroke
				(width 0.1)
				(type default)
			)
			(layer "F.Fab")
		)
		(fp_line
			(start 0.12065 -0.3048)
			(end 0.67945 -0.3048)
			(stroke
				(width 0.1)
				(type default)
			)
			(layer "F.Fab")
		)
		(fp_line
			(start 0.12065 -0.2794)
			(end 0.12065 -0.3048)
			(stroke
				(width 0.1)
				(type default)
			)
			(layer "F.Fab")
		)
		(fp_line
			(start -0.12065 -0.2794)
			(end 0.12065 -0.2794)
			(stroke
				(width 0.1)
				(type default)
			)
			(layer "F.Fab")
		)
		(fp_line
			(start 0.120396 0.2794)
			(end -0.12065 0.2794)
			(stroke
				(width 0.1)
				(type default)
			)
			(layer "F.Fab")
		)
		(fp_line
			(start -0.12065 0.2794)
			(end -0.12065 0.3048)
			(stroke
				(width 0.1)
				(type default)
			)
			(layer "F.Fab")
		)
		(fp_line
			(start 0.67945 0.3048)
			(end 0.120396 0.3048)
			(stroke
				(width 0.1)
				(type default)
			)
			(layer "F.Fab")
		)
		(fp_line
			(start 0.120396 0.3048)
			(end 0.120396 0.2794)
			(stroke
				(width 0.1)
				(type default)
			)
			(layer "F.Fab")
		)
		(fp_line
			(start -0.12065 0.3048)
			(end -0.67945 0.3048)
			(stroke
				(width 0.1)
				(type default)
			)
			(layer "F.Fab")
		)
		(fp_line
			(start -0.67945 0.3048)
			(end -0.67945 -0.305054)
			(stroke
				(width 0.1)
				(type default)
			)
			(layer "F.Fab")
		)
		(pad "1" smd circle
			(at -0.40005 0 90)
			(size 0 0)
			(layers "F.Cu" "F.Mask" "F.Paste")
			(net "PVCCIN_CPU1_VDD6")
		)
		(pad "2" smd circle
			(at 0.40005 0 90)
			(size 0 0)
			(layers "F.Cu" "F.Mask" "F.Paste")
			(net "GND")
		)
	)
)
